(kicad_pcb
	(version 20260206)
	(generator "pcbnew")
	(generator_version "10.0")
	(general
		(thickness 1.6)
		(legacy_teardrops no)
	)
	(paper "A4")
	(title_block
		(title "v2-tray-backplane — ms_tbp_v2.brd")
		(comment 1 "Open CloudServer (Microsoft) / footprints 146-147 of 164")
	)
	(layers
		(0 "F.Cu" signal "TOP")
		(4 "In1.Cu" signal "LYR2")
		(6 "In2.Cu" signal "LYR3")
		(8 "In3.Cu" signal "LYR4")
		(10 "In4.Cu" signal "LYR5")
		(12 "In5.Cu" signal "LYR6")
		(14 "In6.Cu" signal "LYR7")
		(2 "B.Cu" signal "BOTTOM")
		(9 "F.Adhes" user "F.Adhesive")
		(11 "B.Adhes" user "B.Adhesive")
		(13 "F.Paste" user "Package Geometry/Pastemask Top")
		(15 "B.Paste" user "Package Geometry/Pastemask Bottom")
		(5 "F.SilkS" user "Ref Des/Silkscreen Top")
		(7 "B.SilkS" user "Ref Des/Silkscreen Bottom")
		(1 "F.Mask" user "Board Geometry/Soldermask Top")
		(3 "B.Mask" user "Board Geometry/Soldermask Bottom")
		(17 "Dwgs.User" user "User.Drawings")
		(19 "Cmts.User" user "User.Comments")
		(21 "Eco1.User" user "User.Eco1")
		(23 "Eco2.User" user "User.Eco2")
		(25 "Edge.Cuts" user "Board Geometry/Outline")
		(27 "Margin" user)
		(31 "F.CrtYd" user "Package Geometry/Place Bound Top")
		(29 "B.CrtYd" user "Package Geometry/Place Bound Bottom")
		(35 "F.Fab" user "Ref Des/Assembly Top")
		(33 "B.Fab" user "Ref Des/Assembly Bottom")
	)
	(footprint ""
		(layer "F.Cu")
		(at -247.68 45.360001 180)
		(property "Reference" "J11"
			(at 5 16.084901 0)
			(unlocked yes)
			(layer "F.SilkS")
			(effects
				(font
					(size 0.762 0.5334)
					(thickness 0.1016)
				)
			)
		)
		(property "Value" ""
			(at 0 0 180)
			(layer "F.Fab")
			(effects
				(font
					(size 1.27 1.27)
				)
			)
		)
		(duplicate_pad_numbers_are_jumpers no)
		(fp_line
			(start 10.950001 15.3)
			(end -0.950001 15.3)
			(stroke
				(width 0.127)
				(type default)
			)
			(layer "F.SilkS")
		)
		(fp_line
			(start 10.950001 -11.999999)
			(end 10.950001 15.3)
			(stroke
				(width 0.127)
				(type default)
			)
			(layer "F.SilkS")
		)
		(fp_line
			(start -0.950001 15.3)
			(end -0.950001 -11.999999)
			(stroke
				(width 0.127)
				(type default)
			)
			(layer "F.SilkS")
		)
		(fp_line
			(start -0.950001 -11.999999)
			(end 10.950001 -11.999999)
			(stroke
				(width 0.127)
				(type default)
			)
			(layer "F.SilkS")
		)
		(fp_poly
			(pts
				(arc
					(start -4.93 12.500001)
					(mid -3.486036 15.986037)
					(end 0 17.430001)
				)
				(arc
					(start 10 17.430001)
					(mid 13.486036 15.986037)
					(end 14.930001 12.500001)
				)
				(arc
					(start 14.930001 -0.1)
					(mid 13.486037 -3.586037)
					(end 10 -5.03)
				)
				(arc
					(start 0 -5.03)
					(mid -3.486036 -3.586036)
					(end -4.93 -0.1)
				)
			)
			(stroke
				(width 0)
				(type default)
			)
			(fill no)
			(layer "B.CrtYd")
		)
		(fp_poly
			(pts
				(xy 11.949999 16.300001) (xy -1.950001 16.300001) (xy -1.950001 -12.999999) (xy 11.949999 -12.999999)
			)
			(stroke
				(width 0)
				(type default)
			)
			(fill no)
			(layer "F.CrtYd")
		)
		(fp_line
			(start 10.950001 15.3)
			(end -0.950001 15.3)
			(stroke
				(width 0.1)
				(type default)
			)
			(layer "F.Fab")
		)
		(fp_line
			(start 10.950001 -11.999999)
			(end 10.950001 15.3)
			(stroke
				(width 0.1)
				(type default)
			)
			(layer "F.Fab")
		)
		(fp_line
			(start -0.950001 15.3)
			(end -0.950001 -11.999999)
			(stroke
				(width 0.1)
				(type default)
			)
			(layer "F.Fab")
		)
		(fp_line
			(start -0.950001 -11.999999)
			(end 10.950001 -11.999999)
			(stroke
				(width 0.1)
				(type default)
			)
			(layer "F.Fab")
		)
		(fp_text user "I6"
			(at 11.876999 10.9539 0)
			(unlocked yes)
			(layer "F.SilkS")
			(effects
				(font
					(size 0.762 0.5334)
					(thickness 0.1016)
				)
			)
		)
		(fp_text user "E6"
			(at 11.876999 5.353901 0)
			(unlocked yes)
			(layer "F.SilkS")
			(effects
				(font
					(size 0.762 0.5334)
					(thickness 0.1016)
				)
			)
		)
		(fp_text user "A6"
			(at 11.876999 -0.2461 0)
			(unlocked yes)
			(layer "F.SilkS")
			(effects
				(font
					(size 0.762 0.5334)
					(thickness 0.1016)
				)
			)
		)
		(fp_text user "*"
			(at -1.681 -1.204549 0)
			(unlocked yes)
			(layer "F.SilkS")
			(effects
				(font
					(size 0.381 0.381)
					(thickness 0.381)
				)
			)
		)
		(fp_text user "I1"
			(at -1.749999 11.2079 0)
			(unlocked yes)
			(layer "F.SilkS")
			(effects
				(font
					(size 0.762 0.5334)
					(thickness 0.1016)
				)
			)
		)
		(fp_text user "E1"
			(at -1.749999 5.607901 0)
			(unlocked yes)
			(layer "F.SilkS")
			(effects
				(font
					(size 0.762 0.5334)
					(thickness 0.1016)
				)
			)
		)
		(fp_text user "A1"
			(at -1.749999 0.0079 0)
			(unlocked yes)
			(layer "F.SilkS")
			(effects
				(font
					(size 0.762 0.5334)
					(thickness 0.1016)
				)
			)
		)
		(fp_text user "I6"
			(at 11.423 11.0809 0)
			(unlocked yes)
			(layer "B.SilkS")
			(effects
				(font
					(size 0.762 0.5334)
					(thickness 0.1016)
				)
				(justify mirror)
			)
		)
		(fp_text user "E6"
			(at 11.423 5.480901 0)
			(unlocked yes)
			(layer "B.SilkS")
			(effects
				(font
					(size 0.762 0.5334)
					(thickness 0.1016)
				)
				(justify mirror)
			)
		)
		(fp_text user "A6"
			(at 11.423 -0.1191 0)
			(unlocked yes)
			(layer "B.SilkS")
			(effects
				(font
					(size 0.762 0.5334)
					(thickness 0.1016)
				)
				(justify mirror)
			)
		)
		(fp_text user "E1"
			(at -1.26698 5.850301 0)
			(unlocked yes)
			(layer "B.SilkS")
			(effects
				(font
					(size 0.762 0.5334)
					(thickness 0.1016)
				)
				(justify mirror)
			)
		)
		(fp_text user "I1"
			(at -1.5 11.0809 0)
			(unlocked yes)
			(layer "B.SilkS")
			(effects
				(font
					(size 0.762 0.5334)
					(thickness 0.1016)
				)
				(justify mirror)
			)
		)
		(fp_text user "A1"
			(at -1.549999 -0.1191 0)
			(unlocked yes)
			(layer "B.SilkS")
			(effects
				(font
					(size 0.762 0.5334)
					(thickness 0.1016)
				)
				(justify mirror)
			)
		)
		(pad "A1" thru_hole circle
			(at 0 0 180)
			(size 0.8128 0.8128)
			(drill 0.508)
			(layers "*.Cu" "*.Mask")
			(remove_unused_layers no)
			(net "SAS_B1_TX1P")
		)
		(pad "A2" thru_hole circle
			(at 2.000001 -0.1 180)
			(size 0.8128 0.8128)
			(drill 0.508)
			(layers "*.Cu" "*.Mask")
			(remove_unused_layers no)
			(net "GND")
		)
		(pad "A3" thru_hole circle
			(at 4 0 180)
			(size 0.8128 0.8128)
			(drill 0.508)
			(layers "*.Cu" "*.Mask")
			(remove_unused_layers no)
			(net "SERIAL_B1_TX1")
		)
		(pad "A4" thru_hole circle
			(at 6.000001 -0.1 180)
			(size 0.8128 0.8128)
			(drill 0.508)
			(layers "*.Cu" "*.Mask")
			(remove_unused_layers no)
			(net "GND")
		)
		(pad "A5" thru_hole circle
			(at 7.999999 0 180)
			(size 0.8128 0.8128)
			(drill 0.508)
			(layers "*.Cu" "*.Mask")
			(remove_unused_layers no)
			(net "SAS_B1_TX6P")
		)
		(pad "A6" thru_hole circle
			(at 10 -0.1 180)
			(size 0.8128 0.8128)
			(drill 0.508)
			(layers "*.Cu" "*.Mask")
			(remove_unused_layers no)
			(net "GND")
		)
		(pad "B1" thru_hole circle
			(at 0 1.4 180)
			(size 0.8128 0.8128)
			(drill 0.508)
			(layers "*.Cu" "*.Mask")
			(remove_unused_layers no)
			(net "SAS_B1_TX1N")
		)
		(pad "B2" thru_hole circle
			(at 2.000001 1.3 180)
			(size 0.8128 0.8128)
			(drill 0.508)
			(layers "*.Cu" "*.Mask")
			(remove_unused_layers no)
			(net "SAS_B1_RX3P")
		)
		(pad "B3" thru_hole circle
			(at 4 1.4 180)
			(size 0.8128 0.8128)
			(drill 0.508)
			(layers "*.Cu" "*.Mask")
			(remove_unused_layers no)
			(net "SERIAL_B1_RX1")
		)
		(pad "B4" thru_hole circle
			(at 6.000001 1.3 180)
			(size 0.8128 0.8128)
			(drill 0.508)
			(layers "*.Cu" "*.Mask")
			(remove_unused_layers no)
			(net "JBOD_B1_MATED_N")
		)
		(pad "B5" thru_hole circle
			(at 7.999999 1.4 180)
			(size 0.8128 0.8128)
			(drill 0.508)
			(layers "*.Cu" "*.Mask")
			(remove_unused_layers no)
			(net "SAS_B1_TX6N")
		)
		(pad "B6" thru_hole circle
			(at 10 1.3 180)
			(size 0.8128 0.8128)
			(drill 0.508)
			(layers "*.Cu" "*.Mask")
			(remove_unused_layers no)
			(net "SAS_B1_RX8P")
		)
		(pad "C1" thru_hole circle
			(at 0 2.799999 180)
			(size 0.8128 0.8128)
			(drill 0.508)
			(layers "*.Cu" "*.Mask")
			(remove_unused_layers no)
			(net "GND")
		)
		(pad "C2" thru_hole circle
			(at 2.000001 2.7 180)
			(size 0.8128 0.8128)
			(drill 0.508)
			(layers "*.Cu" "*.Mask")
			(remove_unused_layers no)
			(net "SAS_B1_RX3N")
		)
		(pad "C3" thru_hole circle
			(at 4 2.799999 180)
			(size 0.8128 0.8128)
			(drill 0.508)
			(layers "*.Cu" "*.Mask")
			(remove_unused_layers no)
			(net "GND")
		)
		(pad "C4" thru_hole circle
			(at 6.000001 2.7 180)
			(size 0.8128 0.8128)
			(drill 0.508)
			(layers "*.Cu" "*.Mask")
			(remove_unused_layers no)
			(net "BLADE_B1_EN1")
		)
		(pad "C5" thru_hole circle
			(at 7.999999 2.799999 180)
			(size 0.8128 0.8128)
			(drill 0.508)
			(layers "*.Cu" "*.Mask")
			(remove_unused_layers no)
			(net "GND")
		)
		(pad "C6" thru_hole circle
			(at 10 2.7 180)
			(size 0.8128 0.8128)
			(drill 0.508)
			(layers "*.Cu" "*.Mask")
			(remove_unused_layers no)
			(net "SAS_B1_RX8N")
		)
		(pad "D1" thru_hole circle
			(at 0 4.199999 180)
			(size 0.8128 0.8128)
			(drill 0.508)
			(layers "*.Cu" "*.Mask")
			(remove_unused_layers no)
			(net "SAS_B1_RX1P")
		)
		(pad "D2" thru_hole circle
			(at 2.000001 4.099999 180)
			(size 0.8128 0.8128)
			(drill 0.508)
			(layers "*.Cu" "*.Mask")
			(remove_unused_layers no)
			(net "GND")
		)
		(pad "D3" thru_hole circle
			(at 4 4.199999 180)
			(size 0.8128 0.8128)
			(drill 0.508)
			(layers "*.Cu" "*.Mask")
			(remove_unused_layers no)
			(net "SAS_B1_RX4P")
		)
		(pad "D4" thru_hole circle
			(at 6.000001 4.099999 180)
			(size 0.8128 0.8128)
			(drill 0.508)
			(layers "*.Cu" "*.Mask")
			(remove_unused_layers no)
			(net "GND")
		)
		(pad "D5" thru_hole circle
			(at 7.999999 4.199999 180)
			(size 0.8128 0.8128)
			(drill 0.508)
			(layers "*.Cu" "*.Mask")
			(remove_unused_layers no)
			(net "SAS_B1_RX6P")
		)
		(pad "D6" thru_hole circle
			(at 10 4.099999 180)
			(size 0.8128 0.8128)
			(drill 0.508)
			(layers "*.Cu" "*.Mask")
			(remove_unused_layers no)
			(net "GND")
		)
		(pad "E1" thru_hole circle
			(at 0 5.599999 180)
			(size 0.8128 0.8128)
			(drill 0.508)
			(layers "*.Cu" "*.Mask")
			(remove_unused_layers no)
			(net "SAS_B1_RX1N")
		)
		(pad "E2" thru_hole circle
			(at 2.000001 5.499999 180)
			(size 0.8128 0.8128)
			(drill 0.508)
			(layers "*.Cu" "*.Mask")
			(remove_unused_layers no)
			(net "SAS_B1_TX3P")
		)
		(pad "E3" thru_hole circle
			(at 4 5.599999 180)
			(size 0.8128 0.8128)
			(drill 0.508)
			(layers "*.Cu" "*.Mask")
			(remove_unused_layers no)
			(net "SAS_B1_RX4N")
		)
		(pad "E4" thru_hole circle
			(at 6.000001 5.499999 180)
			(size 0.8128 0.8128)
			(drill 0.508)
			(layers "*.Cu" "*.Mask")
			(remove_unused_layers no)
			(net "SAS_B1_TX5P")
		)
		(pad "E5" thru_hole circle
			(at 7.999999 5.599999 180)
			(size 0.8128 0.8128)
			(drill 0.508)
			(layers "*.Cu" "*.Mask")
			(remove_unused_layers no)
			(net "SAS_B1_RX6N")
		)
		(pad "E6" thru_hole circle
			(at 10 5.499999 180)
			(size 0.8128 0.8128)
			(drill 0.508)
			(layers "*.Cu" "*.Mask")
			(remove_unused_layers no)
			(net "SAS_B1_TX8P")
		)
		(pad "F1" thru_hole circle
			(at 0 7.000001 180)
			(size 0.8128 0.8128)
			(drill 0.508)
			(layers "*.Cu" "*.Mask")
			(remove_unused_layers no)
			(net "GND")
		)
		(pad "F2" thru_hole circle
			(at 2.000001 6.899999 180)
			(size 0.8128 0.8128)
			(drill 0.508)
			(layers "*.Cu" "*.Mask")
			(remove_unused_layers no)
			(net "SAS_B1_TX3N")
		)
		(pad "F3" thru_hole circle
			(at 4 7.000001 180)
			(size 0.8128 0.8128)
			(drill 0.508)
			(layers "*.Cu" "*.Mask")
			(remove_unused_layers no)
			(net "GND")
		)
		(pad "F4" thru_hole circle
			(at 6.000001 6.899999 180)
			(size 0.8128 0.8128)
			(drill 0.508)
			(layers "*.Cu" "*.Mask")
			(remove_unused_layers no)
			(net "SAS_B1_TX5N")
		)
		(pad "F5" thru_hole circle
			(at 7.999999 7.000001 180)
			(size 0.8128 0.8128)
			(drill 0.508)
			(layers "*.Cu" "*.Mask")
			(remove_unused_layers no)
			(net "GND")
		)
		(pad "F6" thru_hole circle
			(at 10 6.899999 180)
			(size 0.8128 0.8128)
			(drill 0.508)
			(layers "*.Cu" "*.Mask")
			(remove_unused_layers no)
			(net "SAS_B1_TX8N")
		)
		(pad "G1" thru_hole circle
			(at 0 8.400001 180)
			(size 0.8128 0.8128)
			(drill 0.508)
			(layers "*.Cu" "*.Mask")
			(remove_unused_layers no)
			(net "SAS_B1_TX2P")
		)
		(pad "G2" thru_hole circle
			(at 2.000001 8.300001 180)
			(size 0.8128 0.8128)
			(drill 0.508)
			(layers "*.Cu" "*.Mask")
			(remove_unused_layers no)
			(net "GND")
		)
		(pad "G3" thru_hole circle
			(at 4 8.400001 180)
			(size 0.8128 0.8128)
			(drill 0.508)
			(layers "*.Cu" "*.Mask")
			(remove_unused_layers no)
			(net "SAS_B1_TX4P")
		)
		(pad "G4" thru_hole circle
			(at 6.000001 8.300001 180)
			(size 0.8128 0.8128)
			(drill 0.508)
			(layers "*.Cu" "*.Mask")
			(remove_unused_layers no)
			(net "GND")
		)
		(pad "G5" thru_hole circle
			(at 7.999999 8.400001 180)
			(size 0.8128 0.8128)
			(drill 0.508)
			(layers "*.Cu" "*.Mask")
			(remove_unused_layers no)
			(net "SAS_B1_TX7P")
		)
		(pad "G6" thru_hole circle
			(at 10 8.300001 180)
			(size 0.8128 0.8128)
			(drill 0.508)
			(layers "*.Cu" "*.Mask")
			(remove_unused_layers no)
			(net "GND")
		)
		(pad "H1" thru_hole circle
			(at 0 9.800001 180)
			(size 0.8128 0.8128)
			(drill 0.508)
			(layers "*.Cu" "*.Mask")
			(remove_unused_layers no)
			(net "SAS_B1_TX2N")
		)
		(pad "H2" thru_hole circle
			(at 2.000001 9.700001 180)
			(size 0.8128 0.8128)
			(drill 0.508)
			(layers "*.Cu" "*.Mask")
			(remove_unused_layers no)
			(net "SAS_B1_RX2P")
		)
		(pad "H3" thru_hole circle
			(at 4 9.800001 180)
			(size 0.8128 0.8128)
			(drill 0.508)
			(layers "*.Cu" "*.Mask")
			(remove_unused_layers no)
			(net "SAS_B1_TX4N")
		)
		(pad "H4" thru_hole circle
			(at 6.000001 9.700001 180)
			(size 0.8128 0.8128)
			(drill 0.508)
			(layers "*.Cu" "*.Mask")
			(remove_unused_layers no)
			(net "SAS_B1_RX5P")
		)
		(pad "H5" thru_hole circle
			(at 7.999999 9.800001 180)
			(size 0.8128 0.8128)
			(drill 0.508)
			(layers "*.Cu" "*.Mask")
			(remove_unused_layers no)
			(net "SAS_B1_TX7N")
		)
		(pad "H6" thru_hole circle
			(at 10 9.700001 180)
			(size 0.8128 0.8128)
			(drill 0.508)
			(layers "*.Cu" "*.Mask")
			(remove_unused_layers no)
			(net "SAS_B1_RX7P")
		)
		(pad "I1" thru_hole circle
			(at 0 11.2 180)
			(size 0.8128 0.8128)
			(drill 0.508)
			(layers "*.Cu" "*.Mask")
			(remove_unused_layers no)
			(net "GND")
		)
		(pad "I2" thru_hole circle
			(at 2.000001 11.100001 180)
			(size 0.8128 0.8128)
			(drill 0.508)
			(layers "*.Cu" "*.Mask")
			(remove_unused_layers no)
			(net "SAS_B1_RX2N")
		)
		(pad "I3" thru_hole circle
			(at 4 11.2 180)
			(size 0.8128 0.8128)
			(drill 0.508)
			(layers "*.Cu" "*.Mask")
			(remove_unused_layers no)
			(net "GND")
		)
		(pad "I4" thru_hole circle
			(at 6.000001 11.100001 180)
			(size 0.8128 0.8128)
			(drill 0.508)
			(layers "*.Cu" "*.Mask")
			(remove_unused_layers no)
			(net "SAS_B1_RX5N")
		)
		(pad "I5" thru_hole circle
			(at 7.999999 11.2 180)
			(size 0.8128 0.8128)
			(drill 0.508)
			(layers "*.Cu" "*.Mask")
			(remove_unused_layers no)
			(net "GND")
		)
		(pad "I6" thru_hole circle
			(at 10 11.100001 180)
			(size 0.8128 0.8128)
			(drill 0.508)
			(layers "*.Cu" "*.Mask")
			(remove_unused_layers no)
			(net "SAS_B1_RX7N")
		)
		(pad "J2" thru_hole circle
			(at 2.000001 12.5 180)
			(size 0.8128 0.8128)
			(drill 0.508)
			(layers "*.Cu" "*.Mask")
			(remove_unused_layers no)
			(net "GND")
		)
		(pad "J4" thru_hole circle
			(at 6.000001 12.5 180)
			(size 0.8128 0.8128)
			(drill 0.508)
			(layers "*.Cu" "*.Mask")
			(remove_unused_layers no)
			(net "GND")
		)
		(pad "J6" thru_hole circle
			(at 10 12.5 180)
			(size 0.8128 0.8128)
			(drill 0.508)
			(layers "*.Cu" "*.Mask")
			(remove_unused_layers no)
			(net "GND")
		)
	)
	(footprint ""
		(layer "F.Cu")
		(at -44.831 2.54 180)
		(property "Reference" "R59"
			(at -3.02514 0.01016 0)
			(unlocked yes)
			(layer "F.SilkS")
			(effects
				(font
					(size 0.762 0.5334)
					(thickness 0.1016)
				)
			)
		)
		(property "Value" ""
			(at 0 0 180)
			(layer "F.Fab")
			(effects
				(font
					(size 1.27 1.27)
				)
			)
		)
		(duplicate_pad_numbers_are_jumpers no)
		(fp_line
			(start 0 -0.381)
			(end 0 0.381)
			(stroke
				(width 0.127)
				(type default)
			)
			(layer "F.SilkS")
		)
		(fp_poly
			(pts
				(xy 1.255601 0.656399) (xy -1.255601 0.656399) (xy -1.255601 -0.6564) (xy 1.255601 -0.6564)
			)
			(stroke
				(width 0)
				(type default)
			)
			(fill no)
			(layer "F.CrtYd")
		)
		(fp_line
			(start 0.800001 0.399999)
			(end 0.800001 -0.399999)
			(stroke
				(width 0.1)
				(type default)
			)
			(layer "F.Fab")
		)
		(fp_line
			(start 0.800001 -0.399999)
			(end -0.800001 -0.399999)
			(stroke
				(width 0.1)
				(type default)
			)
			(layer "F.Fab")
		)
		(fp_line
			(start -0.800001 0.399999)
			(end 0.800001 0.399999)
			(stroke
				(width 0.1)
				(type default)
			)
			(layer "F.Fab")
		)
		(fp_line
			(start -0.800001 -0.399999)
			(end -0.800001 0.399999)
			(stroke
				(width 0.1)
				(type default)
			)
			(layer "F.Fab")
		)
		(pad "1" smd rect
			(at -0.650001 0 180)
			(size 0.7112 0.8128)
			(layers "F.Cu" "F.Mask" "F.Paste")
			(net "P3V3_B2_QSFP")
		)
		(pad "2" smd rect
			(at 0.650001 0)
			(size 0.7112 0.8128)
			(layers "F.Cu" "F.Mask" "F.Paste")
			(net "P3V3_40G_B2_VCC_RX")
		)
	)
)
